(kicad_pcb
	(version 20241229)
	(generator "pcbnew")
	(generator_version "9.0")
	(general
		(thickness 1.6642)
		(legacy_teardrops no)
	)
	(paper "A3")
	(title_block
		(title "PolarFire SoM")
		(date "2025-07-22")
		(rev "1.1.4")
		(company "Antmicro Ltd")
		(comment 1 "www.antmicro.com")
		(comment 9 "footprints 80-82 of 470")
	)
	(layers
		(0 "F.Cu" mixed)
		(4 "In1.Cu" power)
		(6 "In2.Cu" signal)
		(8 "In3.Cu" power)
		(10 "In4.Cu" signal)
		(12 "In5.Cu" power)
		(14 "In6.Cu" power)
		(16 "In7.Cu" signal)
		(18 "In8.Cu" power)
		(20 "In9.Cu" signal)
		(22 "In10.Cu" power)
		(24 "In11.Cu" signal)
		(26 "In12.Cu" signal)
		(2 "B.Cu" mixed)
		(9 "F.Adhes" user "F.Adhesive")
		(11 "B.Adhes" user "B.Adhesive")
		(13 "F.Paste" user)
		(15 "B.Paste" user)
		(5 "F.SilkS" user "F.Silkscreen")
		(7 "B.SilkS" user "B.Silkscreen")
		(1 "F.Mask" user)
		(3 "B.Mask" user)
		(17 "Dwgs.User" user "User.Drawings")
		(19 "Cmts.User" user "User.Comments")
		(21 "Eco1.User" user "User.Eco1")
		(23 "Eco2.User" user "User.Eco2")
		(25 "Edge.Cuts" user)
		(27 "Margin" user)
		(31 "F.CrtYd" user "F.Courtyard")
		(29 "B.CrtYd" user "B.Courtyard")
		(35 "F.Fab" user)
		(33 "B.Fab" user)
	)
	(footprint "antmicro-footprints:WLCSP-16_2.25x2.17x0.68mm_Layout4x4_P0.5x0.5mm"
		(layer "F.Cu")
		(at 176.7 147.9)
		(property "Reference" "U6"
			(at -1.67 2.13 0)
			(layer "F.SilkS")
			(effects
				(font
					(size 0.7 0.7)
					(thickness 0.15)
				)
				(justify left bottom)
			)
		)
		(property "Value" "PAC1934T_WLCSP"
			(at 2.25 0.75 0)
			(layer "F.Fab")
			(hide yes)
			(effects
				(font
					(size 0.7 0.7)
					(thickness 0.15)
				)
				(justify left bottom)
			)
		)
		(property "Datasheet" "https://www.mouser.com/datasheet/2/268/PAC1931_Family_Data_Sheet_DS20005850E-1519053.pdf"
			(at 0 0 0)
			(layer "F.Fab")
			(hide yes)
			(effects
				(font
					(size 1.27 1.27)
					(thickness 0.15)
				)
			)
		)
		(property "Description" "DC Power/Energy Monitor With Accumulator, Quad High-side current Sensor, 2.7V to 5.5V, WLCSP-16"
			(at 0 0 0)
			(layer "F.Fab")
			(hide yes)
			(effects
				(font
					(size 1.27 1.27)
					(thickness 0.15)
				)
			)
		)
		(property "Author" "Antmicro"
			(at 0 0 0)
			(layer "F.Fab")
			(hide yes)
			(effects
				(font
					(size 1 1)
					(thickness 0.15)
				)
			)
		)
		(property "License" "Apache-2.0"
			(at 0 0 0)
			(layer "F.Fab")
			(hide yes)
			(effects
				(font
					(size 1 1)
					(thickness 0.15)
				)
			)
		)
		(property "MPN" "PAC1934T-I/J6CX"
			(at 0 0 0)
			(layer "F.Fab")
			(hide yes)
			(effects
				(font
					(size 1 1)
					(thickness 0.15)
				)
			)
		)
		(property "Manufacturer" "Microchip Technology"
			(at 0 0 0)
			(layer "F.Fab")
			(hide yes)
			(effects
				(font
					(size 1 1)
					(thickness 0.15)
				)
			)
		)
		(sheetname "/Supply/")
		(sheetfile "supply.kicad_sch")
		(attr smd)
		(fp_line
			(start -1.2 -0.75)
			(end -0.8 -1.15)
			(stroke
				(width 0.15)
				(type solid)
			)
			(layer "F.SilkS")
		)
		(fp_line
			(start -1.2 1.15)
			(end -1.2 -0.75)
			(stroke
				(width 0.15)
				(type solid)
			)
			(layer "F.SilkS")
		)
		(fp_line
			(start -0.8 -1.15)
			(end 1.2 -1.15)
			(stroke
				(width 0.15)
				(type solid)
			)
			(layer "F.SilkS")
		)
		(fp_line
			(start 1.2 -1.15)
			(end 1.2 1.15)
			(stroke
				(width 0.15)
				(type solid)
			)
			(layer "F.SilkS")
		)
		(fp_line
			(start 1.2 1.15)
			(end -1.2 1.15)
			(stroke
				(width 0.15)
				(type solid)
			)
			(layer "F.SilkS")
		)
		(fp_circle
			(center -1.2 -1.19)
			(end -1.15 -1.19)
			(stroke
				(width 0.15)
				(type solid)
			)
			(fill yes)
			(layer "F.SilkS")
		)
		(fp_rect
			(start -1.35629 -1.35)
			(end 1.354896 1.355248)
			(stroke
				(width 0.05)
				(type solid)
			)
			(fill no)
			(layer "F.CrtYd")
		)
		(fp_text user "License: Apache-2.0"
			(at -2.16 7.4 0)
			(layer "F.Fab")
			(effects
				(font
					(size 0.7 0.7)
					(thickness 0.15)
				)
				(justify left bottom)
			)
		)
		(fp_text user "Author: Antmicro"
			(at -2.16 5 0)
			(layer "F.Fab")
			(effects
				(font
					(size 0.7 0.7)
					(thickness 0.15)
				)
				(justify left bottom)
			)
		)
		(fp_text user "${REFERENCE}"
			(at -2.16 6.2 0)
			(layer "F.Fab")
			(effects
				(font
					(size 0.7 0.7)
					(thickness 0.15)
				)
				(justify left bottom)
			)
		)
		(pad "A1" smd circle
			(at -0.75 -0.75 90)
			(size 0.312 0.312)
			(layers "F.Cu" "F.Mask" "F.Paste")
			(net 577 "Net-(U6-SENSE2+)")
			(pinfunction "SENSE2+")
			(pintype "input")
		)
		(pad "A2" smd circle
			(at -0.25 -0.75 90)
			(size 0.312 0.312)
			(layers "F.Cu" "F.Mask" "F.Paste")
			(net 50 "+3V3")
			(pinfunction "SENSE1-")
			(pintype "input")
		)
		(pad "A3" smd circle
			(at 0.25 -0.75 90)
			(size 0.312 0.312)
			(layers "F.Cu" "F.Mask" "F.Paste")
			(net 576 "Net-(U6-SENSE1+)")
			(pinfunction "SENSE1+")
			(pintype "input")
		)
		(pad "A4" smd circle
			(at 0.75 -0.75 90)
			(size 0.312 0.312)
			(layers "F.Cu" "F.Mask" "F.Paste")
			(net 50 "+3V3")
			(pinfunction "VDD")
			(pintype "power_in")
		)
		(pad "B1" smd circle
			(at -0.75 -0.25 90)
			(size 0.312 0.312)
			(layers "F.Cu" "F.Mask" "F.Paste")
			(net 48 "+1V8")
			(pinfunction "SENSE2-")
			(pintype "input")
		)
		(pad "B2" smd circle
			(at -0.25 -0.25 90)
			(size 0.312 0.312)
			(layers "F.Cu" "F.Mask" "F.Paste")
			(net 649 "VDD")
			(pinfunction "VDD_I/O")
			(pintype "power_in")
		)
		(pad "B3" smd circle
			(at 0.25 -0.25 90)
			(size 0.312 0.312)
			(layers "F.Cu" "F.Mask" "F.Paste")
			(net 263 "Net-(U6-~{PWRDN})")
			(pinfunction "~{PWRDN}")
			(pintype "input")
		)
		(pad "B4" smd circle
			(at 0.75 -0.25 90)
			(size 0.312 0.312)
			(layers "F.Cu" "F.Mask" "F.Paste")
			(net 417 "GND")
			(pinfunction "GND")
			(pintype "power_in")
		)
		(pad "C1" smd circle
			(at -0.75 0.25 90)
			(size 0.312 0.312)
			(layers "F.Cu" "F.Mask" "F.Paste")
			(net 2 "+1V1")
			(pinfunction "SENSE3-")
			(pintype "input")
		)
		(pad "C2" smd circle
			(at -0.25 0.25 90)
			(size 0.312 0.312)
			(layers "F.Cu" "F.Mask" "F.Paste")
			(net 260 "Net-(U6-ADDRSEL)")
			(pinfunction "ADDRSEL")
			(pintype "bidirectional")
		)
		(pad "C3" smd circle
			(at 0.25 0.25 90)
			(size 0.312 0.312)
			(layers "F.Cu" "F.Mask" "F.Paste")
			(net 428 "PAC1934_SLOW")
			(pinfunction "SLOW/~{ALERT}")
			(pintype "bidirectional")
		)
		(pad "C4" smd circle
			(at 0.75 0.25 90)
			(size 0.312 0.312)
			(layers "F.Cu" "F.Mask" "F.Paste")
			(net 92 "/FPGA MSSIO/SUPPLY.SCL")
			(pinfunction "SM_CLK")
			(pintype "input")
		)
		(pad "D1" smd circle
			(at -0.75 0.75 90)
			(size 0.312 0.312)
			(layers "F.Cu" "F.Mask" "F.Paste")
			(net 578 "Net-(U6-SENSE3+)")
			(pinfunction "SENSE3+")
			(pintype "input")
		)
		(pad "D2" smd circle
			(at -0.25 0.75 90)
			(size 0.312 0.312)
			(layers "F.Cu" "F.Mask" "F.Paste")
			(net 96 "+1V2")
			(pinfunction "SENSE4-")
			(pintype "input")
		)
		(pad "D3" smd circle
			(at 0.25 0.75 90)
			(size 0.312 0.312)
			(layers "F.Cu" "F.Mask" "F.Paste")
			(net 579 "Net-(U6-SENSE4+)")
			(pinfunction "SENSE4+")
			(pintype "input")
		)
		(pad "D4" smd circle
			(at 0.75 0.75 90)
			(size 0.312 0.312)
			(layers "F.Cu" "F.Mask" "F.Paste")
			(net 100 "/FPGA MSSIO/SUPPLY.SDA")
			(pinfunction "SM_DATA")
			(pintype "bidirectional")
		)
	)
	(footprint "antmicro-footprints:Tag-Connect_TC2050-IDC-NL_2x5_P1.27mm"
		(layer "F.Cu")
		(at 184.14 118.58 180)
		(property "Reference" "J2"
			(at -2.61 1.98 335.75)
			(layer "F.SilkS")
			(effects
				(font
					(size 0.7 0.7)
					(thickness 0.15)
				)
				(justify left bottom)
			)
		)
		(property "Value" "Tag-Connect_TC2050-IDC-NL_2x5_P1.27mm"
			(at 0 4.4 180)
			(layer "F.Fab")
			(hide yes)
			(effects
				(font
					(size 0.7 0.7)
					(thickness 0.15)
				)
				(justify left bottom)
			)
		)
		(property "Datasheet" "https://www.tag-connect.com/wp-content/uploads/bsk-pdf-manager/TC2050-IDC-NL_Datasheet_8.pdf"
			(at 0 0 180)
			(layer "F.Fab")
			(hide yes)
			(effects
				(font
					(size 1.27 1.27)
					(thickness 0.15)
				)
			)
		)
		(property "Description" "Tag Connect 2x5 1.27mm terminal"
			(at 0 0 180)
			(layer "F.Fab")
			(hide yes)
			(effects
				(font
					(size 1.27 1.27)
					(thickness 0.15)
				)
			)
		)
		(property "Author" "Antmicro"
			(at 368.28 237.16 0)
			(layer "F.Fab")
			(hide yes)
			(effects
				(font
					(size 1 1)
					(thickness 0.15)
				)
			)
		)
		(property "DNP" "DNP"
			(at 368.28 237.16 0)
			(layer "F.Fab")
			(hide yes)
			(effects
				(font
					(size 1 1)
					(thickness 0.15)
				)
			)
		)
		(property "License" "Apache-2.0"
			(at 368.28 237.16 0)
			(layer "F.Fab")
			(hide yes)
			(effects
				(font
					(size 1 1)
					(thickness 0.15)
				)
			)
		)
		(property "MPN" "TC2050-IDC-NL"
			(at 368.28 237.16 0)
			(layer "F.Fab")
			(hide yes)
			(effects
				(font
					(size 1 1)
					(thickness 0.15)
				)
			)
		)
		(property "Manufacturer" "Tag Connect"
			(at 368.28 237.16 0)
			(layer "F.Fab")
			(hide yes)
			(effects
				(font
					(size 1 1)
					(thickness 0.15)
				)
			)
		)
		(sheetname "/FPGA Config/")
		(sheetfile "fpga-config.kicad_sch")
		(attr exclude_from_pos_files exclude_from_bom dnp)
		(fp_line
			(start 5.1 -1.7)
			(end 5.1 1.7)
			(stroke
				(width 0.15)
				(type solid)
			)
			(layer "F.SilkS")
		)
		(fp_line
			(start 4.7 2.049)
			(end 5.1 1.7)
			(stroke
				(width 0.15)
				(type solid)
			)
			(layer "F.SilkS")
		)
		(fp_line
			(start 4.7 2.049)
			(end -2.3 2.049)
			(stroke
				(width 0.15)
				(type solid)
			)
			(layer "F.SilkS")
		)
		(fp_line
			(start 4.7 -2.05)
			(end 5.1 -1.7)
			(stroke
				(width 0.15)
				(type solid)
			)
			(layer "F.SilkS")
		)
		(fp_line
			(start -2.2 -2.05)
			(end 4.7 -2.05)
			(stroke
				(width 0.15)
				(type solid)
			)
			(layer "F.SilkS")
		)
		(fp_line
			(start -2.3 2.049)
			(end -5.08 0.8)
			(stroke
				(width 0.15)
				(type solid)
			)
			(layer "F.SilkS")
		)
		(fp_line
			(start -3.101 1.269)
			(end -3.101 0.4)
			(stroke
				(width 0.15)
				(type solid)
			)
			(layer "F.SilkS")
		)
		(fp_line
			(start -5.08 0.8)
			(end -5.08 -0.9)
			(stroke
				(width 0.15)
				(type solid)
			)
			(layer "F.SilkS")
		)
		(fp_line
			(start -5.08 -0.9)
			(end -2.2 -2.05)
			(stroke
				(width 0.15)
				(type solid)
			)
			(layer "F.SilkS")
		)
		(fp_line
			(start 5.32 -1.8)
			(end 5.32 1.8)
			(stroke
				(width 0.05)
				(type solid)
			)
			(layer "F.CrtYd")
		)
		(fp_line
			(start 4.8 2.29)
			(end 5.32 1.8)
			(stroke
				(width 0.05)
				(type solid)
			)
			(layer "F.CrtYd")
		)
		(fp_line
			(start 4.8 2.29)
			(end -2.4 2.29)
			(stroke
				(width 0.05)
				(type solid)
			)
			(layer "F.CrtYd")
		)
		(fp_line
			(start 4.8 -2.3)
			(end 5.32 -1.8)
			(stroke
				(width 0.05)
				(type solid)
			)
			(layer "F.CrtYd")
		)
		(fp_line
			(start -2.3 -2.3)
			(end 4.8 -2.3)
			(stroke
				(width 0.05)
				(type solid)
			)
			(layer "F.CrtYd")
		)
		(fp_line
			(start -2.4 2.29)
			(end -5.33 1)
			(stroke
				(width 0.05)
				(type solid)
			)
			(layer "F.CrtYd")
		)
		(fp_line
			(start -5.33 1)
			(end -5.33 -1.1)
			(stroke
				(width 0.05)
				(type solid)
			)
			(layer "F.CrtYd")
		)
		(fp_line
			(start -5.33 -1.1)
			(end -2.3 -2.3)
			(stroke
				(width 0.05)
				(type solid)
			)
			(layer "F.CrtYd")
		)
		(fp_text user "License: Apache-2.0"
			(at -6.223 8.449 180)
			(layer "F.Fab")
			(effects
				(font
					(size 0.7 0.7)
					(thickness 0.15)
				)
				(justify left bottom)
			)
		)
		(fp_text user "Author: Antmicro"
			(at -6.223 7.249 180)
			(layer "F.Fab")
			(effects
				(font
					(size 0.7 0.7)
					(thickness 0.15)
				)
				(justify left bottom)
			)
		)
		(fp_text user "${REFERENCE}"
			(at -6.223 6.049 180)
			(layer "F.Fab")
			(effects
				(font
					(size 0.7 0.7)
					(thickness 0.15)
				)
				(justify left bottom)
			)
		)
		(pad "" np_thru_hole circle
			(at -3.81 0 180)
			(size 0.9906 0.9906)
			(drill 0.9906)
			(layers "*.Cu" "*.Mask")
		)
		(pad "" np_thru_hole circle
			(at 3.809 -1.016 180)
			(size 0.9906 0.9906)
			(drill 0.9906)
			(layers "*.Cu" "*.Mask")
		)
		(pad "" np_thru_hole circle
			(at 3.809 1.015 180)
			(size 0.9906 0.9906)
			(drill 0.9906)
			(layers "*.Cu" "*.Mask")
		)
		(pad "1" connect circle
			(at -2.54 0.634 180)
			(size 0.7874 0.7874)
			(layers "F.Cu" "F.Mask")
			(net 124 "JTAG_TCK")
			(pinfunction "1")
			(pintype "passive")
		)
		(pad "2" connect circle
			(at -1.27 0.634 180)
			(size 0.7874 0.7874)
			(layers "F.Cu" "F.Mask")
			(net 417 "GND")
			(pinfunction "2")
			(pintype "passive")
		)
		(pad "3" connect circle
			(at 0 0.634 180)
			(size 0.7874 0.7874)
			(layers "F.Cu" "F.Mask")
			(net 125 "JTAG_TDO")
			(pinfunction "3")
			(pintype "passive")
		)
		(pad "4" connect circle
			(at 1.269 0.634 180)
			(size 0.7874 0.7874)
			(layers "F.Cu" "F.Mask")
			(net 648 "unconnected-(J2-Pad4)")
			(pinfunction "4")
			(pintype "passive+no_connect")
		)
		(pad "5" connect circle
			(at 2.539 0.634 180)
			(size 0.7874 0.7874)
			(layers "F.Cu" "F.Mask")
			(net 123 "JTAG_TMS")
			(pinfunction "5")
			(pintype "passive")
		)
		(pad "6" connect circle
			(at 2.539 -0.635 180)
			(size 0.7874 0.7874)
			(layers "F.Cu" "F.Mask")
			(net 50 "+3V3")
			(pinfunction "6")
			(pintype "passive")
		)
		(pad "7" connect circle
			(at 1.269 -0.635 180)
			(size 0.7874 0.7874)
			(layers "F.Cu" "F.Mask")
			(net 651 "unconnected-(J2-Pad7)")
			(pinfunction "7")
			(pintype "passive+no_connect")
		)
		(pad "8" connect circle
			(at 0 -0.635 180)
			(size 0.7874 0.7874)
			(layers "F.Cu" "F.Mask")
			(net 127 "JTAG_RESET_n")
			(pinfunction "8")
			(pintype "passive")
		)
		(pad "9" connect circle
			(at -1.27 -0.635 180)
			(size 0.7874 0.7874)
			(layers "F.Cu" "F.Mask")
			(net 126 "JTAG_TDI")
			(pinfunction "9")
			(pintype "passive")
		)
		(pad "10" connect circle
			(at -2.54 -0.635 180)
			(size 0.7874 0.7874)
			(layers "F.Cu" "F.Mask")
			(net 417 "GND")
			(pinfunction "10")
			(pintype "passive")
		)
	)
	(footprint "antmicro-footprints:MP_NPTH_Drill2.7mm"
		(locked yes)
		(layer "F.Cu")
		(at 178.017 152.336)
		(property "Reference" "MP2"
			(at 0 -1.8 0)
			(layer "F.SilkS")
			(hide yes)
			(effects
				(font
					(size 0.7 0.7)
					(thickness 0.15)
				)
				(justify left bottom)
			)
		)
		(property "Value" "MP_NPTH_Drill2.7mm"
			(at 0 2.3 0)
			(layer "F.Fab")
			(hide yes)
			(effects
				(font
					(size 0.7 0.7)
					(thickness 0.15)
				)
				(justify left bottom)
			)
		)
		(property "Description" "Mechanical part"
			(at 0 0 0)
			(layer "F.Fab")
			(hide yes)
			(effects
				(font
					(size 1.27 1.27)
					(thickness 0.15)
				)
			)
		)
		(property "Author" "Antmicro"
			(at 0 0 0)
			(layer "F.Fab")
			(hide yes)
			(effects
				(font
					(size 1 1)
					(thickness 0.15)
				)
			)
		)
		(property "License" "Apache-2.0"
			(at 0 0 0)
			(layer "F.Fab")
			(hide yes)
			(effects
				(font
					(size 1 1)
					(thickness 0.15)
				)
			)
		)
		(property "exclude_from_bom" ""
			(at 0 0 0)
			(layer "F.Fab")
			(hide yes)
			(effects
				(font
					(size 1 1)
					(thickness 0.15)
				)
			)
		)
		(sheetfile "polarfire-som.kicad_sch")
		(attr board_only exclude_from_pos_files exclude_from_bom)
		(fp_circle
			(center 0 0)
			(end 1.45 0)
			(stroke
				(width 0.05)
				(type default)
			)
			(fill no)
			(layer "F.CrtYd")
		)
		(fp_text user "License: Apache-2.0"
			(at 0 7.15 0)
			(layer "F.Fab")
			(effects
				(font
					(size 0.7 0.7)
					(thickness 0.15)
				)
				(justify left bottom)
			)
		)
		(fp_text user "Author: Antmicro"
			(at 0 5.95 0)
			(layer "F.Fab")
			(effects
				(font
					(size 0.7 0.7)
					(thickness 0.15)
				)
				(justify left bottom)
			)
		)
		(fp_text user "${REFERENCE}"
			(at 0 4.749 0)
			(layer "F.Fab")
			(effects
				(font
					(size 0.7 0.7)
					(thickness 0.15)
				)
				(justify left bottom)
			)
		)
		(pad "" np_thru_hole circle
			(at 0 0)
			(size 2.7 2.7)
			(drill 2.7)
			(layers "F&B.Cu" "*.Mask")
		)
	)
)
